# BASEBOARD_FAB2 (Tioga Pass) — schematic netlist excerpt (pin names and nets, part order shuffled) for the footprints in the layout excerpt that follows; sources: Cadence DE-HDL packaged netlist, KiCad conversion of Wiwynn_Tioga_Pass_MB.brd

R8E12  RES  4.75K 1% EMPTY  pkg 0402  page 198 : A = P3V3_STBY ; B = FM_CTNR_PS_ON
C8F7  CAP  0.22UF 16V 10% X7R  pkg 0402  page 185 : A = P3E_PCH_TX_0_DP ; B = P3E_PCH_M2_SATA6G_TX_R_DP
R4G1  RES  2 1.0% CHIP  pkg 0402  page 98 : A = M_B_CPU_VREF ; B = M_B_VREF

(kicad_pcb
	(version 20260206)
	(generator "pcbnew")
	(generator_version "10.0")
	(general
		(thickness 1.6)
		(legacy_teardrops no)
	)
	(paper "A4")
	(title_block
		(title "Wiwynn_Tioga_Pass_MB.brd")
		(comment 1 "Tioga Pass / footprints 2207-2209 of 4770")
	)
	(layers
		(0 "F.Cu" signal "TOP")
		(4 "In1.Cu" signal "L2GND")
		(6 "In2.Cu" signal "L3")
		(8 "In3.Cu" signal "L4GND")
		(10 "In4.Cu" signal "L5")
		(12 "In5.Cu" signal "L6GND")
		(14 "In6.Cu" signal "L7VCC")
		(16 "In7.Cu" signal "L8VCC")
		(18 "In8.Cu" signal "L9GND")
		(20 "In9.Cu" signal "L10")
		(22 "In10.Cu" signal "L11GND")
		(24 "In11.Cu" signal "L12")
		(26 "In12.Cu" signal "L13GND")
		(2 "B.Cu" signal "BOTTOM")
		(9 "F.Adhes" user "F.Adhesive")
		(11 "B.Adhes" user "B.Adhesive")
		(13 "F.Paste" user "Package Geometry/Pastemask Top")
		(15 "B.Paste" user "Package Geometry/Pastemask Bottom")
		(5 "F.SilkS" user "Ref Des/Silkscreen Top")
		(7 "B.SilkS" user "Ref Des/Silkscreen Bottom")
		(1 "F.Mask" user "Board Geometry/Soldermask Top")
		(3 "B.Mask" user "Board Geometry/Soldermask Bottom")
		(17 "Dwgs.User" user "User.Drawings")
		(19 "Cmts.User" user "User.Comments")
		(21 "Eco1.User" user "User.Eco1")
		(23 "Eco2.User" user "User.Eco2")
		(25 "Edge.Cuts" user "Board Geometry/Outline")
		(27 "Margin" user)
		(31 "F.CrtYd" user "Package Geometry/Place Bound Top")
		(29 "B.CrtYd" user "Package Geometry/Place Bound Bottom")
		(35 "F.Fab" user "Ref Des/Assembly Top")
		(33 "B.Fab" user "Ref Des/Assembly Bottom")
	)
	(footprint ""
		(layer "F.Cu")
		(at 380.032768 -33.7185 -90)
		(property "Reference" "C8F7"
			(at 0 0 270)
			(layer "F.SilkS")
			(hide yes)
			(effects
				(font
					(size 1.27 1.27)
				)
			)
		)
		(property "Value" ""
			(at 0 0 270)
			(layer "F.Fab")
			(effects
				(font
					(size 1.27 1.27)
				)
			)
		)
		(duplicate_pad_numbers_are_jumpers no)
		(fp_poly
			(pts
				(xy 0.3048 -0.1016) (xy 0.3048 0.9906) (xy -0.3048 0.9906) (xy -0.3048 -0.1016)
			)
			(stroke
				(width 0)
				(type default)
			)
			(fill no)
			(layer "F.CrtYd")
		)
		(fp_line
			(start -0.3048 0.9906)
			(end 0.3048 0.9906)
			(stroke
				(width 0.1)
				(type default)
			)
			(layer "F.Fab")
		)
		(fp_line
			(start 0.3048 0.9906)
			(end 0.3048 -0.1016)
			(stroke
				(width 0.1)
				(type default)
			)
			(layer "F.Fab")
		)
		(fp_line
			(start -0.3048 -0.1016)
			(end -0.3048 0.9906)
			(stroke
				(width 0.1)
				(type default)
			)
			(layer "F.Fab")
		)
		(fp_line
			(start 0.3048 -0.1016)
			(end -0.3048 -0.1016)
			(stroke
				(width 0.1)
				(type default)
			)
			(layer "F.Fab")
		)
		(pad "1" smd rect
			(at 0 0 270)
			(size 0.508 0.508)
			(layers "F.Cu" "F.Mask" "F.Paste")
			(net "P3E_PCH_TX_0_DP")
		)
		(pad "2" smd rect
			(at 0 0.889 270)
			(size 0.508 0.508)
			(layers "F.Cu" "F.Mask" "F.Paste")
			(net "P3E_PCH_M2_SATA6G_TX_R_DP")
		)
		(zone
			(layer "F.Cu")
			(hatch none 0.5)
			(connect_pads
				(clearance 0)
			)
			(min_thickness 0.25)
			(keepout
				(tracks not_allowed)
				(vias allowed)
				(pads allowed)
				(copperpour not_allowed)
				(footprints allowed)
			)
			(placement
				(enabled no)
				(sheetname "")
			)
			(fill
				(thermal_gap 0.5)
				(thermal_bridge_width 0.5)
				(island_removal_mode 0)
			)
			(polygon
				(pts
					(xy 379.397768 -33.9725) (xy 379.397768 -33.4645) (xy 379.778768 -33.4645) (xy 379.778768 -33.9725)
				)
			)
		)
		(zone
			(layer "F.Cu")
			(hatch none 0.5)
			(connect_pads
				(clearance 0)
			)
			(min_thickness 0.25)
			(keepout
				(tracks allowed)
				(vias not_allowed)
				(pads allowed)
				(copperpour not_allowed)
				(footprints allowed)
			)
			(placement
				(enabled no)
				(sheetname "")
			)
			(fill
				(thermal_gap 0.5)
				(thermal_bridge_width 0.5)
				(island_removal_mode 0)
			)
			(polygon
				(pts
					(xy 379.778768 -33.9725) (xy 379.778768 -33.4645) (xy 379.397768 -33.4645) (xy 379.397768 -33.9725)
				)
			)
		)
	)
	(footprint ""
		(layer "F.Cu")
		(at 429.26 -130.7465 180)
		(property "Reference" "R8E12"
			(at 0 0 180)
			(layer "F.SilkS")
			(hide yes)
			(effects
				(font
					(size 1.27 1.27)
				)
			)
		)
		(property "Value" ""
			(at 0 0 180)
			(layer "F.Fab")
			(effects
				(font
					(size 1.27 1.27)
				)
			)
		)
		(duplicate_pad_numbers_are_jumpers no)
		(fp_poly
			(pts
				(xy -0.2794 -0.1016) (xy 0.2794 -0.1016) (xy 0.2794 0.9906) (xy -0.2794 0.9906)
			)
			(stroke
				(width 0)
				(type default)
			)
			(fill no)
			(layer "F.CrtYd")
		)
		(fp_line
			(start 0.2794 0.9906)
			(end 0.2794 -0.1016)
			(stroke
				(width 0.1)
				(type default)
			)
			(layer "F.Fab")
		)
		(fp_line
			(start 0.2794 -0.1016)
			(end -0.2794 -0.1016)
			(stroke
				(width 0.1)
				(type default)
			)
			(layer "F.Fab")
		)
		(fp_line
			(start -0.2794 0.9906)
			(end 0.2794 0.9906)
			(stroke
				(width 0.1)
				(type default)
			)
			(layer "F.Fab")
		)
		(fp_line
			(start -0.2794 -0.1016)
			(end -0.2794 0.9906)
			(stroke
				(width 0.1)
				(type default)
			)
			(layer "F.Fab")
		)
		(pad "1" smd rect
			(at 0 0 180)
			(size 0.508 0.508)
			(layers "F.Cu" "F.Mask" "F.Paste")
			(net "P3V3_STBY")
		)
		(pad "2" smd rect
			(at 0 0.889 180)
			(size 0.508 0.508)
			(layers "F.Cu" "F.Mask" "F.Paste")
			(net "FM_CTNR_PS_ON")
		)
		(zone
			(layer "F.Cu")
			(hatch none 0.5)
			(connect_pads
				(clearance 0)
			)
			(min_thickness 0.25)
			(keepout
				(tracks not_allowed)
				(vias allowed)
				(pads allowed)
				(copperpour not_allowed)
				(footprints allowed)
			)
			(placement
				(enabled no)
				(sheetname "")
			)
			(fill
				(thermal_gap 0.5)
				(thermal_bridge_width 0.5)
				(island_removal_mode 0)
			)
			(polygon
				(pts
					(xy 429.514 -131.3815) (xy 429.006 -131.3815) (xy 429.006 -131.0005) (xy 429.514 -131.0005)
				)
			)
		)
		(zone
			(layer "F.Cu")
			(hatch none 0.5)
			(connect_pads
				(clearance 0)
			)
			(min_thickness 0.25)
			(keepout
				(tracks allowed)
				(vias not_allowed)
				(pads allowed)
				(copperpour not_allowed)
				(footprints allowed)
			)
			(placement
				(enabled no)
				(sheetname "")
			)
			(fill
				(thermal_gap 0.5)
				(thermal_bridge_width 0.5)
				(island_removal_mode 0)
			)
			(polygon
				(pts
					(xy 429.514 -131.0005) (xy 429.006 -131.0005) (xy 429.006 -131.3815) (xy 429.514 -131.3815)
				)
			)
		)
	)
	(footprint ""
		(layer "F.Cu")
		(at 192.786 -13.3985)
		(property "Reference" "R4G1"
			(at 0 0 0)
			(layer "F.SilkS")
			(hide yes)
			(effects
				(font
					(size 1.27 1.27)
				)
			)
		)
		(property "Value" ""
			(at 0 0 0)
			(layer "F.Fab")
			(effects
				(font
					(size 1.27 1.27)
				)
			)
		)
		(duplicate_pad_numbers_are_jumpers no)
		(fp_poly
			(pts
				(xy -0.2794 -0.1016) (xy 0.2794 -0.1016) (xy 0.2794 0.9906) (xy -0.2794 0.9906)
			)
			(stroke
				(width 0)
				(type default)
			)
			(fill no)
			(layer "F.CrtYd")
		)
		(fp_line
			(start -0.2794 -0.1016)
			(end -0.2794 0.9906)
			(stroke
				(width 0.1)
				(type default)
			)
			(layer "F.Fab")
		)
		(fp_line
			(start -0.2794 0.9906)
			(end 0.2794 0.9906)
			(stroke
				(width 0.1)
				(type default)
			)
			(layer "F.Fab")
		)
		(fp_line
			(start 0.2794 -0.1016)
			(end -0.2794 -0.1016)
			(stroke
				(width 0.1)
				(type default)
			)
			(layer "F.Fab")
		)
		(fp_line
			(start 0.2794 0.9906)
			(end 0.2794 -0.1016)
			(stroke
				(width 0.1)
				(type default)
			)
			(layer "F.Fab")
		)
		(pad "1" smd rect
			(at 0 0)
			(size 0.508 0.508)
			(layers "F.Cu" "F.Mask" "F.Paste")
			(net "M_B_CPU_VREF")
		)
		(pad "2" smd rect
			(at 0 0.889)
			(size 0.508 0.508)
			(layers "F.Cu" "F.Mask" "F.Paste")
			(net "M_B_VREF")
		)
		(zone
			(layer "F.Cu")
			(hatch none 0.5)
			(connect_pads
				(clearance 0)
			)
			(min_thickness 0.25)
			(keepout
				(tracks allowed)
				(vias not_allowed)
				(pads allowed)
				(copperpour not_allowed)
				(footprints allowed)
			)
			(placement
				(enabled no)
				(sheetname "")
			)
			(fill
				(thermal_gap 0.5)
				(thermal_bridge_width 0.5)
				(island_removal_mode 0)
			)
			(polygon
				(pts
					(xy 192.532 -13.1445) (xy 193.04 -13.1445) (xy 193.04 -12.7635) (xy 192.532 -12.7635)
				)
			)
		)
		(zone
			(layer "F.Cu")
			(hatch none 0.5)
			(connect_pads
				(clearance 0)
			)
			(min_thickness 0.25)
			(keepout
				(tracks not_allowed)
				(vias allowed)
				(pads allowed)
				(copperpour not_allowed)
				(footprints allowed)
			)
			(placement
				(enabled no)
				(sheetname "")
			)
			(fill
				(thermal_gap 0.5)
				(thermal_bridge_width 0.5)
				(island_removal_mode 0)
			)
			(polygon
				(pts
					(xy 192.532 -12.7635) (xy 193.04 -12.7635) (xy 193.04 -13.1445) (xy 192.532 -13.1445)
				)
			)
		)
	)
)
